(kicad_sch (version 20230121) (generator eeschema)

  (paper "A3")

  (title_block
    (title "Kria K26 Devboard")
    (date "2024-03-26")
    (rev "1.2.5")
    (comment 1 "www.antmicro.com")
    (comment 2 "Antmicro Ltd.")
  )

  (junction (at 55.88 234.315) (diameter 0) (color 0 0 0 0)
  )
  (junction (at 161.29 209.55) (diameter 0) (color 0 0 0 0)
  )
  (junction (at 29.21 245.745) (diameter 0) (color 0 0 0 0)
  )
  (junction (at 55.88 245.745) (diameter 0) (color 0 0 0 0)
  )
  (junction (at 29.21 234.315) (diameter 0) (color 0 0 0 0)
  )
  (junction (at 107.95 236.22) (diameter 0) (color 0 0 0 0)
  )

  (wire (pts (xy 152.4 146.05) (xy 152.4 144.78))
    (stroke (width 0) (type default))
  )
  (wire (pts (xy 152.4 144.78) (xy 177.8 144.78))
    (stroke (width 0) (type default))
  )
  (wire (pts (xy 162.56 33.02) (xy 179.07 33.02))
    (stroke (width 0) (type default))
  )
  (wire (pts (xy 151.13 130.81) (xy 152.4 130.81))
    (stroke (width 0) (type default))
  )
  (wire (pts (xy 223.52 107.95) (xy 248.92 107.95))
    (stroke (width 0) (type default))
  )
  (wire (pts (xy 223.52 100.33) (xy 248.92 100.33))
    (stroke (width 0) (type default))
  )
  (wire (pts (xy 179.07 175.26) (xy 151.13 175.26))
    (stroke (width 0) (type default))
  )
  (wire (pts (xy 250.19 162.56) (xy 248.92 162.56))
    (stroke (width 0) (type default))
  )
  (wire (pts (xy 250.19 205.74) (xy 242.57 205.74))
    (stroke (width 0) (type default))
  )
  (wire (pts (xy 294.64 121.92) (xy 297.18 121.92))
    (stroke (width 0) (type default))
  )
  (wire (pts (xy 248.92 190.5) (xy 229.87 190.5))
    (stroke (width 0) (type default))
  )
  (wire (pts (xy 165.1 27.94) (xy 165.1 30.48))
    (stroke (width 0) (type default))
  )
  (wire (pts (xy 246.38 160.02) (xy 248.92 160.02))
    (stroke (width 0) (type default))
  )
  (wire (pts (xy 152.4 90.17) (xy 177.8 90.17))
    (stroke (width 0) (type default))
  )
  (wire (pts (xy 223.52 53.34) (xy 248.92 53.34))
    (stroke (width 0) (type default))
  )
  (wire (pts (xy 233.68 184.15) (xy 233.68 166.37))
    (stroke (width 0) (type default))
  )
  (wire (pts (xy 298.45 67.31) (xy 298.45 123.19))
    (stroke (width 0) (type default))
  )
  (wire (pts (xy 151.13 228.6) (xy 171.45 228.6))
    (stroke (width 0) (type default))
  )
  (wire (pts (xy 223.52 140.97) (xy 223.52 139.7))
    (stroke (width 0) (type default))
  )
  (wire (pts (xy 250.19 218.44) (xy 222.25 218.44))
    (stroke (width 0) (type default))
  )
  (wire (pts (xy 308.61 80.01) (xy 293.37 80.01))
    (stroke (width 0) (type default))
  )
  (wire (pts (xy 297.18 121.92) (xy 297.18 68.58))
    (stroke (width 0) (type default))
  )
  (wire (pts (xy 248.92 147.32) (xy 246.38 147.32))
    (stroke (width 0) (type default))
  )
  (wire (pts (xy 222.25 154.94) (xy 223.52 154.94))
    (stroke (width 0) (type default))
  )
  (wire (pts (xy 248.92 106.68) (xy 248.92 105.41))
    (stroke (width 0) (type default))
  )
  (wire (pts (xy 152.4 143.51) (xy 177.8 143.51))
    (stroke (width 0) (type default))
  )
  (wire (pts (xy 107.95 236.22) (xy 107.95 254))
    (stroke (width 0) (type default))
  )
  (wire (pts (xy 151.13 233.68) (xy 166.37 233.68))
    (stroke (width 0) (type default))
  )
  (wire (pts (xy 223.52 154.94) (xy 223.52 156.21))
    (stroke (width 0) (type default))
  )
  (wire (pts (xy 311.15 54.61) (xy 311.15 243.84))
    (stroke (width 0) (type default))
  )
  (wire (pts (xy 25.4 238.125) (xy 25.4 234.315))
    (stroke (width 0) (type default))
  )
  (wire (pts (xy 151.13 30.48) (xy 162.56 30.48))
    (stroke (width 0) (type default))
  )
  (wire (pts (xy 250.19 189.23) (xy 248.92 189.23))
    (stroke (width 0) (type default))
  )
  (bus (pts (xy 151.13 17.78) (xy 250.19 17.78))
    (stroke (width 0) (type default))
  )

  (wire (pts (xy 177.8 129.54) (xy 177.8 130.81))
    (stroke (width 0) (type default))
  )
  (wire (pts (xy 107.95 236.22) (xy 102.87 236.22))
    (stroke (width 0) (type default))
  )
  (polyline (pts (xy 12.7 221.615) (xy 77.47 221.615))
    (stroke (width 0) (type default))
  )

  (wire (pts (xy 248.92 109.22) (xy 250.19 109.22))
    (stroke (width 0) (type default))
  )
  (wire (pts (xy 223.52 144.78) (xy 223.52 146.05))
    (stroke (width 0) (type default))
  )
  (wire (pts (xy 165.1 30.48) (xy 179.07 30.48))
    (stroke (width 0) (type default))
  )
  (wire (pts (xy 151.13 201.93) (xy 153.67 201.93))
    (stroke (width 0) (type default))
  )
  (wire (pts (xy 33.02 234.315) (xy 33.02 238.125))
    (stroke (width 0) (type default))
  )
  (wire (pts (xy 177.8 114.3) (xy 177.8 115.57))
    (stroke (width 0) (type default))
  )
  (wire (pts (xy 293.37 144.78) (xy 299.72 144.78))
    (stroke (width 0) (type default))
  )
  (wire (pts (xy 234.95 165.1) (xy 234.95 182.88))
    (stroke (width 0) (type default))
  )
  (wire (pts (xy 222.25 97.79) (xy 223.52 97.79))
    (stroke (width 0) (type default))
  )
  (wire (pts (xy 177.8 152.4) (xy 177.8 153.67))
    (stroke (width 0) (type default))
  )
  (wire (pts (xy 152.4 36.83) (xy 151.13 36.83))
    (stroke (width 0) (type default))
  )
  (wire (pts (xy 59.69 245.745) (xy 59.69 243.205))
    (stroke (width 0) (type default))
  )
  (wire (pts (xy 152.4 99.06) (xy 177.8 99.06))
    (stroke (width 0) (type default))
  )
  (wire (pts (xy 151.13 213.36) (xy 179.07 213.36))
    (stroke (width 0) (type default))
  )
  (wire (pts (xy 222.25 163.83) (xy 223.52 163.83))
    (stroke (width 0) (type default))
  )
  (wire (pts (xy 151.13 77.47) (xy 179.07 77.47))
    (stroke (width 0) (type default))
  )
  (wire (pts (xy 110.49 41.91) (xy 107.95 41.91))
    (stroke (width 0) (type default))
  )
  (wire (pts (xy 152.4 96.52) (xy 152.4 97.79))
    (stroke (width 0) (type default))
  )
  (wire (pts (xy 177.8 96.52) (xy 179.07 96.52))
    (stroke (width 0) (type default))
  )
  (bus (pts (xy 156.21 39.37) (xy 156.21 53.34))
    (stroke (width 0) (type default))
  )

  (wire (pts (xy 151.13 172.72) (xy 179.07 172.72))
    (stroke (width 0) (type default))
  )
  (wire (pts (xy 222.25 50.8) (xy 223.52 50.8))
    (stroke (width 0) (type default))
  )
  (wire (pts (xy 168.91 231.14) (xy 151.13 231.14))
    (stroke (width 0) (type default))
  )
  (wire (pts (xy 223.52 59.69) (xy 248.92 59.69))
    (stroke (width 0) (type default))
  )
  (wire (pts (xy 171.45 228.6) (xy 171.45 241.3))
    (stroke (width 0) (type default))
  )
  (wire (pts (xy 151.13 149.86) (xy 152.4 149.86))
    (stroke (width 0) (type default))
  )
  (bus (pts (xy 222.25 30.48) (xy 250.19 30.48))
    (stroke (width 0) (type default))
  )

  (wire (pts (xy 152.4 106.68) (xy 177.8 106.68))
    (stroke (width 0) (type default))
  )
  (wire (pts (xy 248.92 62.23) (xy 248.92 60.96))
    (stroke (width 0) (type default))
  )
  (wire (pts (xy 228.6 191.77) (xy 248.92 191.77))
    (stroke (width 0) (type default))
  )
  (wire (pts (xy 248.92 181.61) (xy 248.92 182.88))
    (stroke (width 0) (type default))
  )
  (wire (pts (xy 223.52 106.68) (xy 248.92 106.68))
    (stroke (width 0) (type default))
  )
  (wire (pts (xy 52.07 231.775) (xy 55.88 231.775))
    (stroke (width 0) (type default))
  )
  (wire (pts (xy 242.57 254) (xy 242.57 205.74))
    (stroke (width 0) (type default))
  )
  (wire (pts (xy 240.03 175.26) (xy 240.03 156.21))
    (stroke (width 0) (type default))
  )
  (wire (pts (xy 152.4 105.41) (xy 177.8 105.41))
    (stroke (width 0) (type default))
  )
  (wire (pts (xy 151.13 115.57) (xy 152.4 115.57))
    (stroke (width 0) (type default))
  )
  (wire (pts (xy 177.8 146.05) (xy 179.07 146.05))
    (stroke (width 0) (type default))
  )
  (wire (pts (xy 240.03 175.26) (xy 248.92 175.26))
    (stroke (width 0) (type default))
  )
  (wire (pts (xy 152.4 107.95) (xy 152.4 106.68))
    (stroke (width 0) (type default))
  )
  (wire (pts (xy 250.19 166.37) (xy 248.92 166.37))
    (stroke (width 0) (type default))
  )
  (wire (pts (xy 151.13 138.43) (xy 152.4 138.43))
    (stroke (width 0) (type default))
  )
  (wire (pts (xy 177.8 160.02) (xy 152.4 160.02))
    (stroke (width 0) (type default))
  )
  (wire (pts (xy 152.4 138.43) (xy 152.4 137.16))
    (stroke (width 0) (type default))
  )
  (wire (pts (xy 25.4 245.745) (xy 29.21 245.745))
    (stroke (width 0) (type default))
  )
  (wire (pts (xy 151.13 64.77) (xy 179.07 64.77))
    (stroke (width 0) (type default))
  )
  (wire (pts (xy 151.13 153.67) (xy 152.4 153.67))
    (stroke (width 0) (type default))
  )
  (wire (pts (xy 151.13 92.71) (xy 152.4 92.71))
    (stroke (width 0) (type default))
  )
  (wire (pts (xy 152.4 137.16) (xy 177.8 137.16))
    (stroke (width 0) (type default))
  )
  (wire (pts (xy 152.4 129.54) (xy 177.8 129.54))
    (stroke (width 0) (type default))
  )
  (wire (pts (xy 166.37 246.38) (xy 313.69 246.38))
    (stroke (width 0) (type default))
  )
  (wire (pts (xy 222.25 133.35) (xy 223.52 133.35))
    (stroke (width 0) (type default))
  )
  (wire (pts (xy 152.4 97.79) (xy 177.8 97.79))
    (stroke (width 0) (type default))
  )
  (wire (pts (xy 151.13 142.24) (xy 152.4 142.24))
    (stroke (width 0) (type default))
  )
  (wire (pts (xy 153.67 201.93) (xy 153.67 185.42))
    (stroke (width 0) (type default))
  )
  (wire (pts (xy 248.92 97.79) (xy 250.19 97.79))
    (stroke (width 0) (type default))
  )
  (wire (pts (xy 293.37 66.04) (xy 294.64 66.04))
    (stroke (width 0) (type default))
  )
  (wire (pts (xy 152.4 91.44) (xy 177.8 91.44))
    (stroke (width 0) (type default))
  )
  (wire (pts (xy 152.4 134.62) (xy 152.4 135.89))
    (stroke (width 0) (type default))
  )
  (wire (pts (xy 177.8 121.92) (xy 177.8 123.19))
    (stroke (width 0) (type default))
  )
  (wire (pts (xy 248.92 144.78) (xy 250.19 144.78))
    (stroke (width 0) (type default))
  )
  (wire (pts (xy 105.41 233.68) (xy 110.49 233.68))
    (stroke (width 0) (type default))
  )
  (wire (pts (xy 151.13 69.85) (xy 179.07 69.85))
    (stroke (width 0) (type default))
  )
  (wire (pts (xy 25.4 231.775) (xy 29.21 231.775))
    (stroke (width 0) (type default))
  )
  (wire (pts (xy 248.92 50.8) (xy 248.92 52.07))
    (stroke (width 0) (type default))
  )
  (wire (pts (xy 293.37 124.46) (xy 294.64 124.46))
    (stroke (width 0) (type default))
  )
  (wire (pts (xy 102.87 236.22) (xy 102.87 39.37))
    (stroke (width 0) (type default))
  )
  (wire (pts (xy 52.07 243.205) (xy 52.07 245.745))
    (stroke (width 0) (type default))
  )
  (wire (pts (xy 171.45 241.3) (xy 308.61 241.3))
    (stroke (width 0) (type default))
  )
  (wire (pts (xy 297.18 147.32) (xy 297.18 160.02))
    (stroke (width 0) (type default))
  )
  (wire (pts (xy 293.37 120.65) (xy 294.64 120.65))
    (stroke (width 0) (type default))
  )
  (wire (pts (xy 223.52 175.26) (xy 228.6 175.26))
    (stroke (width 0) (type default))
  )
  (wire (pts (xy 248.92 158.75) (xy 250.19 158.75))
    (stroke (width 0) (type default))
  )
  (wire (pts (xy 223.52 138.43) (xy 248.92 138.43))
    (stroke (width 0) (type default))
  )
  (wire (pts (xy 223.52 52.07) (xy 248.92 52.07))
    (stroke (width 0) (type default))
  )
  (wire (pts (xy 222.25 167.64) (xy 223.52 167.64))
    (stroke (width 0) (type default))
  )
  (wire (pts (xy 248.92 148.59) (xy 250.19 148.59))
    (stroke (width 0) (type default))
  )
  (wire (pts (xy 152.4 59.69) (xy 152.4 60.96))
    (stroke (width 0) (type default))
  )
  (wire (pts (xy 223.52 132.08) (xy 248.92 132.08))
    (stroke (width 0) (type default))
  )
  (wire (pts (xy 152.4 119.38) (xy 152.4 120.65))
    (stroke (width 0) (type default))
  )
  (wire (pts (xy 29.21 234.315) (xy 33.02 234.315))
    (stroke (width 0) (type default))
  )
  (wire (pts (xy 223.52 105.41) (xy 223.52 106.68))
    (stroke (width 0) (type default))
  )
  (wire (pts (xy 245.11 161.29) (xy 248.92 161.29))
    (stroke (width 0) (type default))
  )
  (wire (pts (xy 248.92 182.88) (xy 234.95 182.88))
    (stroke (width 0) (type default))
  )
  (wire (pts (xy 293.37 147.32) (xy 297.18 147.32))
    (stroke (width 0) (type default))
  )
  (wire (pts (xy 222.25 54.61) (xy 223.52 54.61))
    (stroke (width 0) (type default))
  )
  (wire (pts (xy 238.76 176.53) (xy 248.92 176.53))
    (stroke (width 0) (type default))
  )
  (wire (pts (xy 162.56 30.48) (xy 162.56 33.02))
    (stroke (width 0) (type default))
  )
  (wire (pts (xy 179.07 72.39) (xy 151.13 72.39))
    (stroke (width 0) (type default))
  )
  (wire (pts (xy 250.19 62.23) (xy 248.92 62.23))
    (stroke (width 0) (type default))
  )
  (wire (pts (xy 248.92 54.61) (xy 248.92 53.34))
    (stroke (width 0) (type default))
  )
  (wire (pts (xy 177.8 119.38) (xy 179.07 119.38))
    (stroke (width 0) (type default))
  )
  (wire (pts (xy 177.8 143.51) (xy 177.8 142.24))
    (stroke (width 0) (type default))
  )
  (wire (pts (xy 248.92 132.08) (xy 248.92 133.35))
    (stroke (width 0) (type default))
  )
  (wire (pts (xy 294.64 69.85) (xy 293.37 69.85))
    (stroke (width 0) (type default))
  )
  (wire (pts (xy 52.07 245.745) (xy 55.88 245.745))
    (stroke (width 0) (type default))
  )
  (wire (pts (xy 223.52 146.05) (xy 243.84 146.05))
    (stroke (width 0) (type default))
  )
  (wire (pts (xy 110.49 80.01) (xy 107.95 80.01))
    (stroke (width 0) (type default))
  )
  (wire (pts (xy 152.4 88.9) (xy 152.4 90.17))
    (stroke (width 0) (type default))
  )
  (wire (pts (xy 229.87 190.5) (xy 229.87 173.99))
    (stroke (width 0) (type default))
  )
  (wire (pts (xy 248.92 146.05) (xy 248.92 144.78))
    (stroke (width 0) (type default))
  )
  (wire (pts (xy 222.25 101.6) (xy 223.52 101.6))
    (stroke (width 0) (type default))
  )
  (wire (pts (xy 294.64 120.65) (xy 294.64 121.92))
    (stroke (width 0) (type default))
  )
  (wire (pts (xy 248.92 147.32) (xy 248.92 148.59))
    (stroke (width 0) (type default))
  )
  (wire (pts (xy 151.13 161.29) (xy 152.4 161.29))
    (stroke (width 0) (type default))
  )
  (wire (pts (xy 248.92 137.16) (xy 250.19 137.16))
    (stroke (width 0) (type default))
  )
  (wire (pts (xy 248.92 100.33) (xy 248.92 101.6))
    (stroke (width 0) (type default))
  )
  (wire (pts (xy 151.13 100.33) (xy 152.4 100.33))
    (stroke (width 0) (type default))
  )
  (bus (pts (xy 222.25 66.04) (xy 250.19 66.04))
    (stroke (width 0) (type default))
  )

  (wire (pts (xy 166.37 233.68) (xy 166.37 246.38))
    (stroke (width 0) (type default))
  )
  (wire (pts (xy 153.67 185.42) (xy 151.13 185.42))
    (stroke (width 0) (type default))
  )
  (wire (pts (xy 152.4 111.76) (xy 152.4 113.03))
    (stroke (width 0) (type default))
  )
  (wire (pts (xy 222.25 172.72) (xy 223.52 172.72))
    (stroke (width 0) (type default))
  )
  (wire (pts (xy 161.29 196.85) (xy 161.29 209.55))
    (stroke (width 0) (type default))
  )
  (wire (pts (xy 248.92 105.41) (xy 250.19 105.41))
    (stroke (width 0) (type default))
  )
  (wire (pts (xy 299.72 144.78) (xy 299.72 251.46))
    (stroke (width 0) (type default))
  )
  (wire (pts (xy 223.52 60.96) (xy 248.92 60.96))
    (stroke (width 0) (type default))
  )
  (wire (pts (xy 248.92 166.37) (xy 248.92 167.64))
    (stroke (width 0) (type default))
  )
  (wire (pts (xy 294.64 68.58) (xy 294.64 69.85))
    (stroke (width 0) (type default))
  )
  (wire (pts (xy 59.69 234.315) (xy 59.69 238.125))
    (stroke (width 0) (type default))
  )
  (wire (pts (xy 177.8 130.81) (xy 179.07 130.81))
    (stroke (width 0) (type default))
  )
  (wire (pts (xy 248.92 170.18) (xy 250.19 170.18))
    (stroke (width 0) (type default))
  )
  (wire (pts (xy 248.92 129.54) (xy 250.19 129.54))
    (stroke (width 0) (type default))
  )
  (wire (pts (xy 248.92 168.91) (xy 248.92 170.18))
    (stroke (width 0) (type default))
  )
  (bus (pts (xy 156.21 39.37) (xy 151.13 39.37))
    (stroke (width 0) (type default))
  )

  (wire (pts (xy 177.8 160.02) (xy 177.8 161.29))
    (stroke (width 0) (type default))
  )
  (wire (pts (xy 223.52 139.7) (xy 248.92 139.7))
    (stroke (width 0) (type default))
  )
  (wire (pts (xy 152.4 114.3) (xy 177.8 114.3))
    (stroke (width 0) (type default))
  )
  (wire (pts (xy 223.52 130.81) (xy 248.92 130.81))
    (stroke (width 0) (type default))
  )
  (wire (pts (xy 152.4 113.03) (xy 177.8 113.03))
    (stroke (width 0) (type default))
  )
  (wire (pts (xy 152.4 115.57) (xy 152.4 114.3))
    (stroke (width 0) (type default))
  )
  (wire (pts (xy 248.92 162.56) (xy 248.92 161.29))
    (stroke (width 0) (type default))
  )
  (wire (pts (xy 248.92 177.8) (xy 250.19 177.8))
    (stroke (width 0) (type default))
  )
  (wire (pts (xy 229.87 173.99) (xy 223.52 173.99))
    (stroke (width 0) (type default))
  )
  (wire (pts (xy 250.19 181.61) (xy 248.92 181.61))
    (stroke (width 0) (type default))
  )
  (wire (pts (xy 152.4 121.92) (xy 177.8 121.92))
    (stroke (width 0) (type default))
  )
  (wire (pts (xy 152.4 128.27) (xy 177.8 128.27))
    (stroke (width 0) (type default))
  )
  (wire (pts (xy 248.92 191.77) (xy 248.92 193.04))
    (stroke (width 0) (type default))
  )
  (wire (pts (xy 222.25 82.55) (xy 250.19 82.55))
    (stroke (width 0) (type default))
  )
  (wire (pts (xy 248.92 176.53) (xy 248.92 177.8))
    (stroke (width 0) (type default))
  )
  (wire (pts (xy 151.13 96.52) (xy 152.4 96.52))
    (stroke (width 0) (type default))
  )
  (wire (pts (xy 248.92 107.95) (xy 248.92 109.22))
    (stroke (width 0) (type default))
  )
  (wire (pts (xy 179.07 74.93) (xy 151.13 74.93))
    (stroke (width 0) (type default))
  )
  (wire (pts (xy 177.8 138.43) (xy 179.07 138.43))
    (stroke (width 0) (type default))
  )
  (wire (pts (xy 222.25 105.41) (xy 223.52 105.41))
    (stroke (width 0) (type default))
  )
  (wire (pts (xy 55.88 245.745) (xy 59.69 245.745))
    (stroke (width 0) (type default))
  )
  (wire (pts (xy 248.92 99.06) (xy 248.92 97.79))
    (stroke (width 0) (type default))
  )
  (wire (pts (xy 160.02 59.69) (xy 152.4 59.69))
    (stroke (width 0) (type default))
  )
  (wire (pts (xy 163.83 236.22) (xy 163.83 248.92))
    (stroke (width 0) (type default))
  )
  (bus (pts (xy 222.25 80.01) (xy 250.19 80.01))
    (stroke (width 0) (type default))
  )

  (wire (pts (xy 177.8 92.71) (xy 179.07 92.71))
    (stroke (width 0) (type default))
  )
  (wire (pts (xy 222.25 144.78) (xy 223.52 144.78))
    (stroke (width 0) (type default))
  )
  (wire (pts (xy 151.13 57.15) (xy 152.4 57.15))
    (stroke (width 0) (type default))
  )
  (wire (pts (xy 152.4 92.71) (xy 152.4 91.44))
    (stroke (width 0) (type default))
  )
  (wire (pts (xy 223.52 147.32) (xy 242.57 147.32))
    (stroke (width 0) (type default))
  )
  (wire (pts (xy 151.13 33.02) (xy 152.4 33.02))
    (stroke (width 0) (type default))
  )
  (wire (pts (xy 151.13 218.44) (xy 179.07 218.44))
    (stroke (width 0) (type default))
  )
  (wire (pts (xy 223.52 60.96) (xy 223.52 62.23))
    (stroke (width 0) (type default))
  )
  (wire (pts (xy 246.38 222.25) (xy 250.19 222.25))
    (stroke (width 0) (type default))
  )
  (wire (pts (xy 223.52 163.83) (xy 223.52 165.1))
    (stroke (width 0) (type default))
  )
  (wire (pts (xy 55.88 247.015) (xy 55.88 245.745))
    (stroke (width 0) (type default))
  )
  (wire (pts (xy 223.52 133.35) (xy 223.52 132.08))
    (stroke (width 0) (type default))
  )
  (wire (pts (xy 110.49 236.22) (xy 107.95 236.22))
    (stroke (width 0) (type default))
  )
  (wire (pts (xy 25.4 243.205) (xy 25.4 245.745))
    (stroke (width 0) (type default))
  )
  (wire (pts (xy 100.33 77.47) (xy 100.33 257.81))
    (stroke (width 0) (type default))
  )
  (wire (pts (xy 223.52 99.06) (xy 248.92 99.06))
    (stroke (width 0) (type default))
  )
  (wire (pts (xy 177.8 151.13) (xy 177.8 149.86))
    (stroke (width 0) (type default))
  )
  (wire (pts (xy 223.52 129.54) (xy 223.52 130.81))
    (stroke (width 0) (type default))
  )
  (wire (pts (xy 223.52 137.16) (xy 223.52 138.43))
    (stroke (width 0) (type default))
  )
  (wire (pts (xy 223.52 167.64) (xy 223.52 166.37))
    (stroke (width 0) (type default))
  )
  (wire (pts (xy 248.92 189.23) (xy 248.92 190.5))
    (stroke (width 0) (type default))
  )
  (wire (pts (xy 177.8 100.33) (xy 179.07 100.33))
    (stroke (width 0) (type default))
  )
  (wire (pts (xy 223.52 62.23) (xy 222.25 62.23))
    (stroke (width 0) (type default))
  )
  (wire (pts (xy 179.07 215.9) (xy 151.13 215.9))
    (stroke (width 0) (type default))
  )
  (wire (pts (xy 223.52 156.21) (xy 240.03 156.21))
    (stroke (width 0) (type default))
  )
  (wire (pts (xy 177.8 134.62) (xy 179.07 134.62))
    (stroke (width 0) (type default))
  )
  (wire (pts (xy 222.25 148.59) (xy 223.52 148.59))
    (stroke (width 0) (type default))
  )
  (wire (pts (xy 248.92 173.99) (xy 250.19 173.99))
    (stroke (width 0) (type default))
  )
  (wire (pts (xy 152.4 142.24) (xy 152.4 143.51))
    (stroke (width 0) (type default))
  )
  (wire (pts (xy 52.07 234.315) (xy 55.88 234.315))
    (stroke (width 0) (type default))
  )
  (wire (pts (xy 222.25 176.53) (xy 223.52 176.53))
    (stroke (width 0) (type default))
  )
  (wire (pts (xy 177.8 135.89) (xy 177.8 134.62))
    (stroke (width 0) (type default))
  )
  (wire (pts (xy 151.13 27.94) (xy 165.1 27.94))
    (stroke (width 0) (type default))
  )
  (wire (pts (xy 151.13 123.19) (xy 152.4 123.19))
    (stroke (width 0) (type default))
  )
  (bus (pts (xy 222.25 93.98) (xy 250.19 93.98))
    (stroke (width 0) (type default))
  )

  (wire (pts (xy 222.25 137.16) (xy 223.52 137.16))
    (stroke (width 0) (type default))
  )
  (wire (pts (xy 248.92 140.97) (xy 250.19 140.97))
    (stroke (width 0) (type default))
  )
  (wire (pts (xy 248.92 167.64) (xy 243.84 167.64))
    (stroke (width 0) (type default))
  )
  (wire (pts (xy 177.8 115.57) (xy 179.07 115.57))
    (stroke (width 0) (type default))
  )
  (polyline (pts (xy 77.47 271.145) (xy 77.47 284.48))
    (stroke (width 0) (type default))
  )

  (wire (pts (xy 107.95 196.85) (xy 161.29 196.85))
    (stroke (width 0) (type default))
  )
  (wire (pts (xy 316.23 19.05) (xy 316.23 248.92))
    (stroke (width 0) (type default))
  )
  (wire (pts (xy 223.52 166.37) (xy 233.68 166.37))
    (stroke (width 0) (type default))
  )
  (wire (pts (xy 33.02 245.745) (xy 33.02 243.205))
    (stroke (width 0) (type default))
  )
  (wire (pts (xy 107.95 254) (xy 242.57 254))
    (stroke (width 0) (type default))
  )
  (wire (pts (xy 152.4 33.02) (xy 152.4 34.29))
    (stroke (width 0) (type default))
  )
  (wire (pts (xy 152.4 58.42) (xy 158.75 58.42))
    (stroke (width 0) (type default))
  )
  (wire (pts (xy 250.19 50.8) (xy 248.92 50.8))
    (stroke (width 0) (type default))
  )
  (wire (pts (xy 158.75 35.56) (xy 158.75 58.42))
    (stroke (width 0) (type default))
  )
  (wire (pts (xy 223.52 172.72) (xy 223.52 173.99))
    (stroke (width 0) (type default))
  )
  (wire (pts (xy 297.18 68.58) (xy 294.64 68.58))
    (stroke (width 0) (type default))
  )
  (wire (pts (xy 308.61 80.01) (xy 308.61 241.3))
    (stroke (width 0) (type default))
  )
  (wire (pts (xy 29.21 234.315) (xy 29.21 231.775))
    (stroke (width 0) (type default))
  )
  (wire (pts (xy 152.4 120.65) (xy 177.8 120.65))
    (stroke (width 0) (type default))
  )
  (wire (pts (xy 107.95 80.01) (xy 107.95 196.85))
    (stroke (width 0) (type default))
  )
  (wire (pts (xy 151.13 157.48) (xy 152.4 157.48))
    (stroke (width 0) (type default))
  )
  (wire (pts (xy 179.07 67.31) (xy 151.13 67.31))
    (stroke (width 0) (type default))
  )
  (wire (pts (xy 222.25 234.95) (xy 250.19 234.95))
    (stroke (width 0) (type default))
  )
  (wire (pts (xy 151.13 111.76) (xy 152.4 111.76))
    (stroke (width 0) (type default))
  )
  (wire (pts (xy 222.25 109.22) (xy 223.52 109.22))
    (stroke (width 0) (type default))
  )
  (wire (pts (xy 151.13 119.38) (xy 152.4 119.38))
    (stroke (width 0) (type default))
  )
  (wire (pts (xy 151.13 127) (xy 152.4 127))
    (stroke (width 0) (type default))
  )
  (wire (pts (xy 25.4 234.315) (xy 29.21 234.315))
    (stroke (width 0) (type default))
  )
  (wire (pts (xy 242.57 168.91) (xy 248.92 168.91))
    (stroke (width 0) (type default))
  )
  (wire (pts (xy 222.25 58.42) (xy 223.52 58.42))
    (stroke (width 0) (type default))
  )
  (wire (pts (xy 151.13 104.14) (xy 152.4 104.14))
    (stroke (width 0) (type default))
  )
  (wire (pts (xy 152.4 135.89) (xy 177.8 135.89))
    (stroke (width 0) (type default))
  )
  (polyline (pts (xy 77.47 221.615) (xy 77.47 271.145))
    (stroke (width 0) (type default))
  )

  (wire (pts (xy 223.52 101.6) (xy 223.52 100.33))
    (stroke (width 0) (type default))
  )
  (wire (pts (xy 152.4 149.86) (xy 152.4 151.13))
    (stroke (width 0) (type default))
  )
  (wire (pts (xy 177.8 123.19) (xy 179.07 123.19))
    (stroke (width 0) (type default))
  )
  (wire (pts (xy 250.19 54.61) (xy 248.92 54.61))
    (stroke (width 0) (type default))
  )
  (wire (pts (xy 107.95 52.07) (xy 110.49 52.07))
    (stroke (width 0) (type default))
  )
  (wire (pts (xy 151.13 209.55) (xy 161.29 209.55))
    (stroke (width 0) (type default))
  )
  (wire (pts (xy 248.92 185.42) (xy 250.19 185.42))
    (stroke (width 0) (type default))
  )
  (wire (pts (xy 248.92 139.7) (xy 248.92 140.97))
    (stroke (width 0) (type default))
  )
  (wire (pts (xy 299.72 251.46) (xy 105.41 251.46))
    (stroke (width 0) (type default))
  )
  (wire (pts (xy 152.4 123.19) (xy 152.4 121.92))
    (stroke (width 0) (type default))
  )
  (wire (pts (xy 238.76 157.48) (xy 238.76 176.53))
    (stroke (width 0) (type default))
  )
  (wire (pts (xy 177.8 107.95) (xy 179.07 107.95))
    (stroke (width 0) (type default))
  )
  (wire (pts (xy 248.92 193.04) (xy 250.19 193.04))
    (stroke (width 0) (type default))
  )
  (wire (pts (xy 177.8 88.9) (xy 179.07 88.9))
    (stroke (width 0) (type default))
  )
  (wire (pts (xy 152.4 153.67) (xy 152.4 152.4))
    (stroke (width 0) (type default))
  )
  (wire (pts (xy 151.13 134.62) (xy 152.4 134.62))
    (stroke (width 0) (type default))
  )
  (wire (pts (xy 152.4 157.48) (xy 152.4 158.75))
    (stroke (width 0) (type default))
  )
  (wire (pts (xy 52.07 238.125) (xy 52.07 234.315))
    (stroke (width 0) (type default))
  )
  (wire (pts (xy 177.8 113.03) (xy 177.8 111.76))
    (stroke (width 0) (type default))
  )
  (wire (pts (xy 55.88 234.315) (xy 55.88 231.775))
    (stroke (width 0) (type default))
  )
  (wire (pts (xy 316.23 19.05) (xy 293.37 19.05))
    (stroke (width 0) (type default))
  )
  (wire (pts (xy 29.21 247.015) (xy 29.21 245.745))
    (stroke (width 0) (type default))
  )
  (wire (pts (xy 151.13 166.37) (xy 179.07 166.37))
    (stroke (width 0) (type default))
  )
  (wire (pts (xy 177.8 142.24) (xy 179.07 142.24))
    (stroke (width 0) (type default))
  )
  (wire (pts (xy 179.07 220.98) (xy 151.13 220.98))
    (stroke (width 0) (type default))
  )
  (wire (pts (xy 177.8 144.78) (xy 177.8 146.05))
    (stroke (width 0) (type default))
  )
  (wire (pts (xy 177.8 158.75) (xy 177.8 157.48))
    (stroke (width 0) (type default))
  )
  (wire (pts (xy 105.41 251.46) (xy 105.41 233.68))
    (stroke (width 0) (type default))
  )
  (wire (pts (xy 177.8 104.14) (xy 179.07 104.14))
    (stroke (width 0) (type default))
  )
  (wire (pts (xy 107.95 41.91) (xy 107.95 52.07))
    (stroke (width 0) (type default))
  )
  (wire (pts (xy 152.4 104.14) (xy 152.4 105.41))
    (stroke (width 0) (type default))
  )
  (wire (pts (xy 248.92 101.6) (xy 250.19 101.6))
    (stroke (width 0) (type default))
  )
  (wire (pts (xy 223.52 58.42) (xy 223.52 59.69))
    (stroke (width 0) (type default))
  )
  (wire (pts (xy 223.52 157.48) (xy 223.52 158.75))
    (stroke (width 0) (type default))
  )
  (wire (pts (xy 223.52 50.8) (xy 223.52 52.07))
    (stroke (width 0) (type default))
  )
  (wire (pts (xy 177.8 105.41) (xy 177.8 104.14))
    (stroke (width 0) (type default))
  )
  (wire (pts (xy 152.4 158.75) (xy 177.8 158.75))
    (stroke (width 0) (type default))
  )
  (wire (pts (xy 177.8 149.86) (xy 179.07 149.86))
    (stroke (width 0) (type default))
  )
  (wire (pts (xy 151.13 80.01) (xy 179.07 80.01))
    (stroke (width 0) (type default))
  )
  (wire (pts (xy 177.8 90.17) (xy 177.8 88.9))
    (stroke (width 0) (type default))
  )
  (wire (pts (xy 248.92 146.05) (xy 245.11 146.05))
    (stroke (width 0) (type default))
  )
  (wire (pts (xy 222.25 215.9) (xy 250.19 215.9))
    (stroke (width 0) (type default))
  )
  (wire (pts (xy 153.67 41.91) (xy 151.13 41.91))
    (stroke (width 0) (type default))
  )
  (wire (pts (xy 177.8 111.76) (xy 179.07 111.76))
    (stroke (width 0) (type default))
  )
  (wire (pts (xy 168.91 243.84) (xy 168.91 231.14))
    (stroke (width 0) (type default))
  )
  (wire (pts (xy 248.92 138.43) (xy 248.92 137.16))
    (stroke (width 0) (type default))
  )
  (wire (pts (xy 223.52 158.75) (xy 222.25 158.75))
    (stroke (width 0) (type default))
  )
  (wire (pts (xy 152.4 57.15) (xy 152.4 58.42))
    (stroke (width 0) (type default))
  )
  (wire (pts (xy 177.8 106.68) (xy 177.8 107.95))
    (stroke (width 0) (type default))
  )
  (wire (pts (xy 152.4 130.81) (xy 152.4 129.54))
    (stroke (width 0) (type default))
  )
  (wire (pts (xy 223.52 109.22) (xy 223.52 107.95))
    (stroke (width 0) (type default))
  )
  (wire (pts (xy 228.6 175.26) (xy 228.6 191.77))
    (stroke (width 0) (type default))
  )
  (wire (pts (xy 177.8 97.79) (xy 177.8 96.52))
    (stroke (width 0) (type default))
  )
  (wire (pts (xy 163.83 236.22) (xy 151.13 236.22))
    (stroke (width 0) (type default))
  )
  (bus (pts (xy 222.25 232.41) (xy 250.19 232.41))
    (stroke (width 0) (type default))
  )

  (wire (pts (xy 152.4 60.96) (xy 151.13 60.96))
    (stroke (width 0) (type default))
  )
  (wire (pts (xy 248.92 133.35) (xy 250.19 133.35))
    (stroke (width 0) (type default))
  )
  (wire (pts (xy 152.4 161.29) (xy 152.4 160.02))
    (stroke (width 0) (type default))
  )
  (wire (pts (xy 29.21 245.745) (xy 33.02 245.745))
    (stroke (width 0) (type default))
  )
  (wire (pts (xy 293.37 50.8) (xy 313.69 50.8))
    (stroke (width 0) (type default))
  )
  (wire (pts (xy 248.92 175.26) (xy 248.92 173.99))
    (stroke (width 0) (type default))
  )
  (bus (pts (xy 151.13 53.34) (xy 156.21 53.34))
    (stroke (width 0) (type default))
  )

  (wire (pts (xy 297.18 160.02) (xy 293.37 160.02))
    (stroke (width 0) (type default))
  )
  (wire (pts (xy 222.25 129.54) (xy 223.52 129.54))
    (stroke (width 0) (type default))
  )
  (wire (pts (xy 151.13 224.79) (xy 179.07 224.79))
    (stroke (width 0) (type default))
  )
  (wire (pts (xy 242.57 147.32) (xy 242.57 168.91))
    (stroke (width 0) (type default))
  )
  (wire (pts (xy 152.4 127) (xy 152.4 128.27))
    (stroke (width 0) (type default))
  )
  (wire (pts (xy 177.8 157.48) (xy 179.07 157.48))
    (stroke (width 0) (type default))
  )
  (wire (pts (xy 152.4 100.33) (xy 152.4 99.06))
    (stroke (width 0) (type default))
  )
  (wire (pts (xy 161.29 209.55) (xy 179.07 209.55))
    (stroke (width 0) (type default))
  )
  (wire (pts (xy 223.52 176.53) (xy 223.52 175.26))
    (stroke (width 0) (type default))
  )
  (wire (pts (xy 55.88 234.315) (xy 59.69 234.315))
    (stroke (width 0) (type default))
  )
  (wire (pts (xy 151.13 146.05) (xy 152.4 146.05))
    (stroke (width 0) (type default))
  )
  (wire (pts (xy 294.64 124.46) (xy 294.64 123.19))
    (stroke (width 0) (type default))
  )
  (wire (pts (xy 151.13 107.95) (xy 152.4 107.95))
    (stroke (width 0) (type default))
  )
  (wire (pts (xy 158.75 35.56) (xy 152.4 35.56))
    (stroke (width 0) (type default))
  )
  (wire (pts (xy 151.13 50.8) (xy 153.67 50.8))
    (stroke (width 0) (type default))
  )
  (wire (pts (xy 163.83 248.92) (xy 316.23 248.92))
    (stroke (width 0) (type default))
  )
  (wire (pts (xy 177.8 120.65) (xy 177.8 119.38))
    (stroke (width 0) (type default))
  )
  (wire (pts (xy 177.8 137.16) (xy 177.8 138.43))
    (stroke (width 0) (type default))
  )
  (wire (pts (xy 246.38 257.81) (xy 100.33 257.81))
    (stroke (width 0) (type default))
  )
  (polyline (pts (xy 12.7 254.635) (xy 77.47 254.635))
    (stroke (width 0) (type default))
  )

  (wire (pts (xy 233.68 184.15) (xy 248.92 184.15))
    (stroke (width 0) (type default))
  )
  (wire (pts (xy 238.76 157.48) (xy 223.52 157.48))
    (stroke (width 0) (type default))
  )
  (wire (pts (xy 248.92 184.15) (xy 248.92 185.42))
    (stroke (width 0) (type default))
  )
  (wire (pts (xy 177.8 127) (xy 179.07 127))
    (stroke (width 0) (type default))
  )
  (wire (pts (xy 177.8 161.29) (xy 179.07 161.29))
    (stroke (width 0) (type default))
  )
  (wire (pts (xy 152.4 34.29) (xy 160.02 34.29))
    (stroke (width 0) (type default))
  )
  (wire (pts (xy 248.92 130.81) (xy 248.92 129.54))
    (stroke (width 0) (type default))
  )
  (wire (pts (xy 177.8 99.06) (xy 177.8 100.33))
    (stroke (width 0) (type default))
  )
  (wire (pts (xy 102.87 39.37) (xy 110.49 39.37))
    (stroke (width 0) (type default))
  )
  (wire (pts (xy 245.11 146.05) (xy 245.11 161.29))
    (stroke (width 0) (type default))
  )
  (wire (pts (xy 153.67 50.8) (xy 153.67 41.91))
    (stroke (width 0) (type default))
  )
  (wire (pts (xy 222.25 140.97) (xy 223.52 140.97))
    (stroke (width 0) (type default))
  )
  (wire (pts (xy 294.64 66.04) (xy 294.64 67.31))
    (stroke (width 0) (type default))
  )
  (wire (pts (xy 234.95 165.1) (xy 223.52 165.1))
    (stroke (width 0) (type default))
  )
  (wire (pts (xy 223.52 148.59) (xy 223.52 147.32))
    (stroke (width 0) (type default))
  )
  (wire (pts (xy 152.4 152.4) (xy 177.8 152.4))
    (stroke (width 0) (type default))
  )
  (wire (pts (xy 151.13 88.9) (xy 152.4 88.9))
    (stroke (width 0) (type default))
  )
  (wire (pts (xy 246.38 147.32) (xy 246.38 160.02))
    (stroke (width 0) (type default))
  )
  (wire (pts (xy 294.64 67.31) (xy 298.45 67.31))
    (stroke (width 0) (type default))
  )
  (wire (pts (xy 294.64 123.19) (xy 298.45 123.19))
    (stroke (width 0) (type default))
  )
  (wire (pts (xy 311.15 243.84) (xy 168.91 243.84))
    (stroke (width 0) (type default))
  )
  (wire (pts (xy 177.8 128.27) (xy 177.8 127))
    (stroke (width 0) (type default))
  )
  (wire (pts (xy 179.07 168.91) (xy 151.13 168.91))
    (stroke (width 0) (type default))
  )
  (wire (pts (xy 160.02 34.29) (xy 160.02 59.69))
    (stroke (width 0) (type default))
  )
  (wire (pts (xy 246.38 222.25) (xy 246.38 257.81))
    (stroke (width 0) (type default))
  )
  (wire (pts (xy 152.4 151.13) (xy 177.8 151.13))
    (stroke (width 0) (type default))
  )
  (wire (pts (xy 313.69 50.8) (xy 313.69 246.38))
    (stroke (width 0) (type default))
  )
  (wire (pts (xy 177.8 153.67) (xy 179.07 153.67))
    (stroke (width 0) (type default))
  )
  (wire (pts (xy 177.8 91.44) (xy 177.8 92.71))
    (stroke (width 0) (type default))
  )
  (wire (pts (xy 248.92 59.69) (xy 248.92 58.42))
    (stroke (width 0) (type default))
  )
  (wire (pts (xy 243.84 146.05) (xy 243.84 167.64))
    (stroke (width 0) (type default))
  )
  (wire (pts (xy 248.92 160.02) (xy 248.92 158.75))
    (stroke (width 0) (type default))
  )
  (wire (pts (xy 152.4 35.56) (xy 152.4 36.83))
    (stroke (width 0) (type default))
  )
  (wire (pts (xy 100.33 77.47) (xy 110.49 77.47))
    (stroke (width 0) (type default))
  )
  (wire (pts (xy 223.52 97.79) (xy 223.52 99.06))
    (stroke (width 0) (type default))
  )
  (wire (pts (xy 223.52 54.61) (xy 223.52 53.34))
    (stroke (width 0) (type default))
  )
  (wire (pts (xy 293.37 54.61) (xy 311.15 54.61))
    (stroke (width 0) (type default))
  )
  (wire (pts (xy 248.92 58.42) (xy 250.19 58.42))
    (stroke (width 0) (type default))
  )

  (text "Logos" (at 12.7 258.445 0)
    (effects (font (size 1.27 1.27) (thickness 0.254) bold) (justify left bottom))
  )
  (text "Shield to GND connection" (at 12.7 225.425 0)
    (effects (font (size 1.27 1.27) (thickness 0.254) bold) (justify left bottom))
  )
  (text "K26 SOM" (at 191.77 120.65 0)
    (effects (font (size 2.54 2.54) (thickness 0.508) bold) (justify left bottom))
  )

  (global_label "SH_UP" (shape input) (at 52.07 231.775 180) (fields_autoplaced)
    (effects (font (size 1.27 1.27)) (justify right))
    (property "Intersheetrefs" "${INTERSHEET_REFS}" (at 302.26 186.055 0)
      (effects (font (size 1.27 1.27)) hide)
    )
  )
  (global_label "SH_DOWN" (shape input) (at 25.4 231.775 180) (fields_autoplaced)
    (effects (font (size 1.27 1.27)) (justify right))
    (property "Intersheetrefs" "${INTERSHEET_REFS}" (at 275.59 212.725 0)
      (effects (font (size 1.27 1.27)) hide)
    )
  )

  (symbol (lib_id "kria-k26-devboard:R_330R_0402") (at 25.4 238.125 270) (unit 1)
    (in_bom yes) (on_board yes) (dnp no)
    (property "Reference" "R1" (at 26.67 239.3951 90)
      (effects (font (size 1.524 1.524)) (justify left))
    )
    (property "Value" "R_330R_0402" (at 21.59 238.125 0)
      (effects (font (size 1.27 1.27) (thickness 0.15)) (justify left bottom) hide)
    )
    (property "Footprint" "kria-k26-devboard-footprints:R_0402_1005Metric" (at 30.48 243.205 0)
      (effects (font (size 1.27 1.27) (thickness 0.15)) (justify left bottom) hide)
    )
    (property "Datasheet" "https://www.bourns.com/docs/product-datasheets/cr.pdf" (at 25.4 238.125 0)
      (effects (font (size 1.27 1.27) (thickness 0.15)) (justify left bottom) hide)
    )
    (property "Manufacturer" "Bourns" (at 35.56 243.205 0)
      (effects (font (size 1.27 1.27) (thickness 0.15)) (justify left bottom) hide)
    )
    (property "MPN" "CR0402-FX-3300GLF" (at 33.02 243.205 0)
      (effects (font (size 1.27 1.27) (thickness 0.15)) (justify left bottom) hide)
    )
    (property "Val" "330R" (at 26.67 242.57 90)
      (effects (font (size 1.27 1.27) (thickness 0.15)) (justify left))
    )
    (property "License" "Apache-2.0" (at 0 258.445 0)
      (effects (font (size 1.27 1.27) (thickness 0.15)) (justify left bottom) hide)
    )
    (property "Author" "Antmicro" (at -2.54 258.445 0)
      (effects (font (size 1.27 1.27) (thickness 0.15)) (justify left bottom) hide)
    )
    (property "Tolerance" "1%" (at 15.24 258.445 0)
      (effects (font (size 1.27 1.27)) (justify left bottom) hide)
    )
    (pin "1")
    (pin "2")
    (instances
      (project "kria-k26-devboard"
        (path ""
          (reference "R1") (unit 1)
        )
      )
    )
  )

  (symbol (lib_id "kria-k26-devboard:C_100n_0402") (at 33.02 238.125 270) (unit 1)
    (in_bom yes) (on_board yes) (dnp no)
    (property "Reference" "C1" (at 33.655 238.76 90)
      (effects (font (size 1.524 1.524)) (justify left))
    )
    (property "Value" "C_100n_0402" (at 29.21 238.125 0)
      (effects (font (size 1.27 1.27) (thickness 0.15)) (justify left bottom) hide)
    )
    (property "Footprint" "kria-k26-devboard-footprints:C_0402_1005Metric" (at 38.1 243.205 0)
      (effects (font (size 1.27 1.27) (thickness 0.15)) (justify left bottom) hide)
    )
    (property "Datasheet" "https://search.murata.co.jp/Ceramy/image/img/A01X/G101/ENG/GRM155R61H104KE14-01.pdf" (at 33.02 238.125 0)
      (effects (font (size 1.27 1.27) (thickness 0.15)) (justify left bottom) hide)
    )
    (property "Manufacturer" "Murata" (at 43.18 243.205 0)
      (effects (font (size 1.27 1.27) (thickness 0.15)) (justify left bottom) hide)
    )
    (property "MPN" "GRM155R61H104KE14D" (at 40.64 243.205 0)
      (effects (font (size 1.27 1.27) (thickness 0.15)) (justify left bottom) hide)
    )
    (property "Val" "100n" (at 33.655 242.57 90)
      (effects (font (size 1.27 1.27) (thickness 0.15)) (justify left))
    )
    (property "License" "Apache-2.0" (at 10.16 258.445 0)
      (effects (font (size 1.27 1.27) (thickness 0.15)) (justify left bottom) hide)
    )
    (property "Author" "Antmicro" (at 7.62 258.445 0)
      (effects (font (size 1.27 1.27) (thickness 0.15)) (justify left bottom) hide)
    )
    (property "Voltage" "50V" (at 5.08 258.445 0)
      (effects (font (size 1.27 1.27)) (justify left bottom) hide)
    )
    (property "Dielectric" "X5R" (at 2.54 258.445 0)
      (effects (font (size 1.27 1.27)) (justify left bottom) hide)
    )
    (pin "1")
    (pin "2")
    (instances
      (project "kria-k26-devboard"
        (path ""
          (reference "C1") (unit 1)
        )
      )
    )
  )

  (symbol (lib_id "kria-k26-devboard:GND") (at 29.21 247.015 0) (unit 1)
    (in_bom yes) (on_board yes) (dnp no)
    (property "Reference" "#PWR01" (at 29.21 253.365 0)
      (effects (font (size 1.27 1.27)) hide)
    )
    (property "Value" "GND" (at 29.337 251.4092 0)
      (effects (font (size 1.27 1.27)))
    )
    (property "Footprint" "" (at 38.1 254.635 0)
      (effects (font (size 1.27 1.27) (thickness 0.15)) (justify left bottom) hide)
    )
    (property "Datasheet" "" (at 38.1 259.715 0)
      (effects (font (size 1.27 1.27) (thickness 0.15)) (justify left bottom) hide)
    )
    (property "Author" "Antmicro" (at 38.1 254.635 0)
      (effects (font (size 1.27 1.27) (thickness 0.15)) (justify left bottom) hide)
    )
    (property "License" "Apache-2.0" (at 38.1 257.175 0)
      (effects (font (size 1.27 1.27) (thickness 0.15)) (justify left bottom) hide)
    )
    (pin "1")
    (instances
      (project "kria-k26-devboard"
        (path ""
          (reference "#PWR01") (unit 1)
        )
      )
    )
  )

  (symbol (lib_id "kria-k26-devboard:R_330R_0402") (at 52.07 238.125 270) (unit 1)
    (in_bom yes) (on_board yes) (dnp no)
    (property "Reference" "R2" (at 53.34 239.3951 90)
      (effects (font (size 1.524 1.524)) (justify left))
    )
    (property "Value" "R_330R_0402" (at 48.26 238.125 0)
      (effects (font (size 1.27 1.27) (thickness 0.15)) (justify left bottom) hide)
    )
    (property "Footprint" "kria-k26-devboard-footprints:R_0402_1005Metric" (at 57.15 243.205 0)
      (effects (font (size 1.27 1.27) (thickness 0.15)) (justify left bottom) hide)
    )
    (property "Datasheet" "https://www.bourns.com/docs/product-datasheets/cr.pdf" (at 52.07 238.125 0)
      (effects (font (size 1.27 1.27) (thickness 0.15)) (justify left bottom) hide)
    )
    (property "Manufacturer" "Bourns" (at 62.23 243.205 0)
      (effects (font (size 1.27 1.27) (thickness 0.15)) (justify left bottom) hide)
    )
    (property "MPN" "CR0402-FX-3300GLF" (at 59.69 243.205 0)
      (effects (font (size 1.27 1.27) (thickness 0.15)) (justify left bottom) hide)
    )
    (property "Val" "330R" (at 53.34 242.57 90)
      (effects (font (size 1.27 1.27) (thickness 0.15)) (justify left))
    )
    (property "License" "Apache-2.0" (at 26.67 258.445 0)
      (effects (font (size 1.27 1.27) (thickness 0.15)) (justify left bottom) hide)
    )
    (property "Author" "Antmicro" (at 24.13 258.445 0)
      (effects (font (size 1.27 1.27) (thickness 0.15)) (justify left bottom) hide)
    )
    (property "Tolerance" "1%" (at 41.91 258.445 0)
      (effects (font (size 1.27 1.27)) (justify left bottom) hide)
    )
    (pin "1")
    (pin "2")
    (instances
      (project "kria-k26-devboard"
        (path ""
          (reference "R2") (unit 1)
        )
      )
    )
  )

  (symbol (lib_id "kria-k26-devboard:C_100n_0402") (at 59.69 238.125 270) (unit 1)
    (in_bom yes) (on_board yes) (dnp no)
    (property "Reference" "C2" (at 60.325 238.76 90)
      (effects (font (size 1.524 1.524)) (justify left))
    )
    (property "Value" "C_100n_0402" (at 55.88 238.125 0)
      (effects (font (size 1.27 1.27) (thickness 0.15)) (justify left bottom) hide)
    )
    (property "Footprint" "kria-k26-devboard-footprints:C_0402_1005Metric" (at 64.77 243.205 0)
      (effects (font (size 1.27 1.27) (thickness 0.15)) (justify left bottom) hide)
    )
    (property "Datasheet" "https://search.murata.co.jp/Ceramy/image/img/A01X/G101/ENG/GRM155R61H104KE14-01.pdf" (at 59.69 238.125 0)
      (effects (font (size 1.27 1.27) (thickness 0.15)) (justify left bottom) hide)
    )
    (property "Manufacturer" "Murata" (at 69.85 243.205 0)
      (effects (font (size 1.27 1.27) (thickness 0.15)) (justify left bottom) hide)
    )
    (property "MPN" "GRM155R61H104KE14D" (at 67.31 243.205 0)
      (effects (font (size 1.27 1.27) (thickness 0.15)) (justify left bottom) hide)
    )
    (property "Val" "100n" (at 60.325 242.57 90)
      (effects (font (size 1.27 1.27) (thickness 0.15)) (justify left))
    )
    (property "License" "Apache-2.0" (at 36.83 258.445 0)
      (effects (font (size 1.27 1.27) (thickness 0.15)) (justify left bottom) hide)
    )
    (property "Author" "Antmicro" (at 34.29 258.445 0)
      (effects (font (size 1.27 1.27) (thickness 0.15)) (justify left bottom) hide)
    )
    (property "Voltage" "50V" (at 31.75 258.445 0)
      (effects (font (size 1.27 1.27)) (justify left bottom) hide)
    )
    (property "Dielectric" "X5R" (at 29.21 258.445 0)
      (effects (font (size 1.27 1.27)) (justify left bottom) hide)
    )
    (pin "1")
    (pin "2")
    (instances
      (project "kria-k26-devboard"
        (path ""
          (reference "C2") (unit 1)
        )
      )
    )
  )

  (symbol (lib_id "kria-k26-devboard:GND") (at 55.88 247.015 0) (unit 1)
    (in_bom yes) (on_board yes) (dnp no)
    (property "Reference" "#PWR02" (at 55.88 253.365 0)
      (effects (font (size 1.27 1.27)) hide)
    )
    (property "Value" "GND" (at 56.007 251.4092 0)
      (effects (font (size 1.27 1.27)))
    )
    (property "Footprint" "" (at 64.77 254.635 0)
      (effects (font (size 1.27 1.27) (thickness 0.15)) (justify left bottom) hide)
    )
    (property "Datasheet" "" (at 64.77 259.715 0)
      (effects (font (size 1.27 1.27) (thickness 0.15)) (justify left bottom) hide)
    )
    (property "Author" "Antmicro" (at 64.77 254.635 0)
      (effects (font (size 1.27 1.27) (thickness 0.15)) (justify left bottom) hide)
    )
    (property "License" "Apache-2.0" (at 64.77 257.175 0)
      (effects (font (size 1.27 1.27) (thickness 0.15)) (justify left bottom) hide)
    )
    (pin "1")
    (instances
      (project "kria-k26-devboard"
        (path ""
          (reference "#PWR02") (unit 1)
        )
      )
    )
  )

  (symbol (lib_id "kria-k26-devboard:oshw_logo") (at 52.07 262.89 0) (unit 1)
    (in_bom yes) (on_board yes) (dnp no) (fields_autoplaced)
    (property "Reference" "N2" (at 58.42 260.5975 0)
      (effects (font (size 1.27 1.27)) (justify left))
    )
    (property "Value" "oshw_logo" (at 58.42 263.1375 0)
      (effects (font (size 1.27 1.27) (thickness 0.15)) (justify left))
    )
    (property "Footprint" "kria-k26-devboard-footprints:oshw-logo" (at 52.578 268.986 0)
      (effects (font (size 1.27 1.27) (thickness 0.15)) (justify left bottom) hide)
    )
    (property "Datasheet" "" (at 52.07 262.89 0)
      (effects (font (size 1.27 1.27) (thickness 0.15)) (justify left bottom) hide)
    )
    (property "Author" "Antmicro" (at 67.31 278.13 0)
      (effects (font (size 1.27 1.27) (thickness 0.15)) (justify left bottom) hide)
    )
    (property "License" "Apache-2.0" (at 67.31 280.67 0)
      (effects (font (size 1.27 1.27) (thickness 0.15)) (justify left bottom) hide)
    )
    (property "MPN" "" (at 52.07 262.89 0)
      (effects (font (size 1.27 1.27)) hide)
    )
    (property "Manufacturer" "" (at 67.31 283.21 0)
      (effects (font (size 1.27 1.27) (thickness 0.15)) (justify left bottom) hide)
    )
    (instances
      (project "kria-k26-devboard"
        (path ""
          (reference "N2") (unit 1)
        )
      )
    )
  )

  (symbol (lib_id "kria-k26-devboard:antmicro_logo") (at 25.4 262.89 0) (unit 1)
    (in_bom yes) (on_board yes) (dnp no) (fields_autoplaced)
    (property "Reference" "N1" (at 31.75 260.5975 0)
      (effects (font (size 1.27 1.27)) (justify left))
    )
    (property "Value" "antmicro_logo" (at 31.75 263.1375 0)
      (effects (font (size 1.27 1.27) (thickness 0.15)) (justify left))
    )
    (property "Footprint" "kria-k26-devboard-footprints:antmicro-logo" (at 22.86 256.54 0)
      (effects (font (size 1.27 1.27) (thickness 0.15)) (justify left bottom) hide)
    )
    (property "Datasheet" "" (at 25.4 254 0)
      (effects (font (size 1.27 1.27) (thickness 0.15)) (justify left bottom) hide)
    )
    (property "MPN" "" (at 25.4 262.89 0)
      (effects (font (size 1.27 1.27)) hide)
    )
    (property "Manufacturer" "" (at 40.64 283.21 0)
      (effects (font (size 1.27 1.27) (thickness 0.15)) (justify left bottom) hide)
    )
    (property "Author" "Antmicro" (at 40.64 278.13 0)
      (effects (font (size 1.27 1.27) (thickness 0.15)) (justify left bottom) hide)
    )
    (property "License" "Apache-2.0" (at 40.64 280.67 0)
      (effects (font (size 1.27 1.27) (thickness 0.15)) (justify left bottom) hide)
    )
    (instances
      (project "kria-k26-devboard"
        (path ""
          (reference "N1") (unit 1)
        )
      )
    )
  )

  (sheet (at 179.07 27.94) (size 43.18 209.55) (fields_autoplaced)
    (stroke (width 0) (type solid))
    (fill (color 0 0 0 0.0000))
    (property "Sheetname" "Xilinx K26 SOM" (at 179.07 27.2284 0)
      (effects (font (size 1.27 1.27)) (justify left bottom))
    )
    (property "Sheetfile" "k26_som.kicad_sch" (at 179.07 238.0746 0)
      (effects (font (size 1.27 1.27)) (justify left top))
    )
    (pin "MIO[64..77]" input (at 222.25 30.48 0)
      (effects (font (size 1.27 1.27)) (justify right))
    )
    (pin "VCCO_EN_PL_M2C" input (at 179.07 33.02 180)
      (effects (font (size 1.27 1.27)) (justify left))
    )
    (pin "VCCO_EN_PS_M2C" input (at 179.07 30.48 180)
      (effects (font (size 1.27 1.27)) (justify left))
    )
    (pin "MIO[52..63]" bidirectional (at 222.25 66.04 0)
      (effects (font (size 1.27 1.27)) (justify right))
    )
    (pin "GTR_DP2_C2M_P" input (at 222.25 58.42 0)
      (effects (font (size 1.27 1.27)) (justify right))
    )
    (pin "GTR_DP2_C2M_N" input (at 222.25 62.23 0)
      (effects (font (size 1.27 1.27)) (justify right))
    )
    (pin "GTR_DP2_M2C_P" input (at 222.25 50.8 0)
      (effects (font (size 1.27 1.27)) (justify right))
    )
    (pin "GTR_DP2_M2C_N" input (at 222.25 54.61 0)
      (effects (font (size 1.27 1.27)) (justify right))
    )
    (pin "MIO[45..51]" input (at 222.25 80.01 0)
      (effects (font (size 1.27 1.27)) (justify right))
    )
    (pin "MIO39" input (at 222.25 82.55 0)
      (effects (font (size 1.27 1.27)) (justify right))
    )
    (pin "MIO[27..30]" input (at 222.25 93.98 0)
      (effects (font (size 1.27 1.27)) (justify right))
    )
    (pin "GTR_DP0_M2C_P" input (at 222.25 97.79 0)
      (effects (font (size 1.27 1.27)) (justify right))
    )
    (pin "GTR_DP0_M2C_N" input (at 222.25 101.6 0)
      (effects (font (size 1.27 1.27)) (justify right))
    )
    (pin "GTR_DP1_M2C_P" input (at 222.25 105.41 0)
      (effects (font (size 1.27 1.27)) (justify right))
    )
    (pin "GTR_DP1_M2C_N" input (at 222.25 109.22 0)
      (effects (font (size 1.27 1.27)) (justify right))
    )
    (pin "GTR_REFCLK3_C2M_P" input (at 222.25 144.78 0)
      (effects (font (size 1.27 1.27)) (justify right))
    )
    (pin "GTR_REFCLK3_C2M_N" input (at 222.25 148.59 0)
      (effects (font (size 1.27 1.27)) (justify right))
    )
    (pin "GTR_DP3_C2M_P" input (at 222.25 129.54 0)
      (effects (font (size 1.27 1.27)) (justify right))
    )
    (pin "GTR_DP3_C2M_N" input (at 222.25 133.35 0)
      (effects (font (size 1.27 1.27)) (justify right))
    )
    (pin "GTR_DP3_M2C_P" input (at 222.25 137.16 0)
      (effects (font (size 1.27 1.27)) (justify right))
    )
    (pin "GTR_DP3_M2C_N" input (at 222.25 140.97 0)
      (effects (font (size 1.27 1.27)) (justify right))
    )
    (pin "HPA00_CC_P" input (at 179.07 88.9 180)
      (effects (font (size 1.27 1.27)) (justify left))
    )
    (pin "HPA00_CC_N" input (at 179.07 92.71 180)
      (effects (font (size 1.27 1.27)) (justify left))
    )
    (pin "HPA03_P" input (at 179.07 111.76 180)
      (effects (font (size 1.27 1.27)) (justify left))
    )
    (pin "HPA03_N" input (at 179.07 115.57 180)
      (effects (font (size 1.27 1.27)) (justify left))
    )
    (pin "HPA08_P" input (at 179.07 149.86 180)
      (effects (font (size 1.27 1.27)) (justify left))
    )
    (pin "HPA08_N" input (at 179.07 153.67 180)
      (effects (font (size 1.27 1.27)) (justify left))
    )
    (pin "HPA02_P" input (at 179.07 104.14 180)
      (effects (font (size 1.27 1.27)) (justify left))
    )
    (pin "HPA02_N" input (at 179.07 107.95 180)
      (effects (font (size 1.27 1.27)) (justify left))
    )
    (pin "HPA01_P" input (at 179.07 96.52 180)
      (effects (font (size 1.27 1.27)) (justify left))
    )
    (pin "HPA01_N" input (at 179.07 100.33 180)
      (effects (font (size 1.27 1.27)) (justify left))
    )
    (pin "HPA09_P" input (at 179.07 157.48 180)
      (effects (font (size 1.27 1.27)) (justify left))
    )
    (pin "HPA09_N" input (at 179.07 161.29 180)
      (effects (font (size 1.27 1.27)) (justify left))
    )
    (pin "HPA05_CC_P" input (at 179.07 127 180)
      (effects (font (size 1.27 1.27)) (justify left))
    )
    (pin "HPA05_CC_N" input (at 179.07 130.81 180)
      (effects (font (size 1.27 1.27)) (justify left))
    )
    (pin "HPA06_P" input (at 179.07 134.62 180)
      (effects (font (size 1.27 1.27)) (justify left))
    )
    (pin "HPA06_N" input (at 179.07 138.43 180)
      (effects (font (size 1.27 1.27)) (justify left))
    )
    (pin "HPA04_P" input (at 179.07 119.38 180)
      (effects (font (size 1.27 1.27)) (justify left))
    )
    (pin "HPA04_N" input (at 179.07 123.19 180)
      (effects (font (size 1.27 1.27)) (justify left))
    )
    (pin "HPA07_P" input (at 179.07 142.24 180)
      (effects (font (size 1.27 1.27)) (justify left))
    )
    (pin "HPA07_N" input (at 179.07 146.05 180)
      (effects (font (size 1.27 1.27)) (justify left))
    )
    (pin "HDA00_C" input (at 179.07 168.91 180)
      (effects (font (size 1.27 1.27)) (justify left))
    )
    (pin "HDA01" input (at 179.07 166.37 180)
      (effects (font (size 1.27 1.27)) (justify left))
    )
    (pin "MIO38" input (at 179.07 213.36 180)
      (effects (font (size 1.27 1.27)) (justify left))
    )
    (pin "MIO44" input (at 179.07 220.98 180)
      (effects (font (size 1.27 1.27)) (justify left))
    )
    (pin "MIO43" input (at 179.07 218.44 180)
      (effects (font (size 1.27 1.27)) (justify left))
    )
    (pin "HDA04" input (at 179.07 172.72 180)
      (effects (font (size 1.27 1.27)) (justify left))
    )
    (pin "HDA02" input (at 179.07 224.79 180)
      (effects (font (size 1.27 1.27)) (justify left))
    )
    (pin "HDA09" input (at 179.07 175.26 180)
      (effects (font (size 1.27 1.27)) (justify left))
    )
    (pin "MIO36" input (at 179.07 64.77 180)
      (effects (font (size 1.27 1.27)) (justify left))
    )
    (pin "MIO37" input (at 179.07 67.31 180)
      (effects (font (size 1.27 1.27)) (justify left))
    )
    (pin "JTAG_TMS_C2M" input (at 179.07 72.39 180)
      (effects (font (size 1.27 1.27)) (justify left))
    )
    (pin "JTAG_TDO_M2C" input (at 179.07 69.85 180)
      (effects (font (size 1.27 1.27)) (justify left))
    )
    (pin "JTAG_TDI_C2M" input (at 179.07 77.47 180)
      (effects (font (size 1.27 1.27)) (justify left))
    )
    (pin "JTAG_TCK_C2M" input (at 179.07 74.93 180)
      (effects (font (size 1.27 1.27)) (justify left))
    )
    (pin "MIO24_I2C_SCK" input (at 222.25 215.9 0)
      (effects (font (size 1.27 1.27)) (justify right))
    )
    (pin "MIO25_I2C_SDA" input (at 222.25 218.44 0)
      (effects (font (size 1.27 1.27)) (justify right))
    )
    (pin "HDA[11..18]" input (at 222.25 232.41 0)
      (effects (font (size 1.27 1.27)) (justify right))
    )
    (pin "HDA16_CC" input (at 222.25 234.95 0)
      (effects (font (size 1.27 1.27)) (justify right))
    )
    (pin "~{PS_POR}" input (at 179.07 209.55 180)
      (effects (font (size 1.27 1.27)) (justify left))
    )
    (pin "GTR_REFCLK2_C2M_P" input (at 222.25 154.94 0)
      (effects (font (size 1.27 1.27)) (justify right))
    )
    (pin "GTR_REFCLK2_C2M_N" input (at 222.25 158.75 0)
      (effects (font (size 1.27 1.27)) (justify right))
    )
    (pin "GTR_REFCLK1_C2M_P" input (at 222.25 163.83 0)
      (effects (font (size 1.27 1.27)) (justify right))
    )
    (pin "GTR_REFCLK1_C2M_N" input (at 222.25 167.64 0)
      (effects (font (size 1.27 1.27)) (justify right))
    )
    (pin "GTR_REFCLK0_C2M_P" input (at 222.25 172.72 0)
      (effects (font (size 1.27 1.27)) (justify right))
    )
    (pin "GTR_REFCLK0_C2M_N" input (at 222.25 176.53 0)
      (effects (font (size 1.27 1.27)) (justify right))
    )
    (pin "MIO41" input (at 179.07 215.9 180)
      (effects (font (size 1.27 1.27)) (justify left))
    )
    (pin "~{PS_SRST_C2M}" input (at 179.07 80.01 180)
      (effects (font (size 1.27 1.27)) (justify left))
    )
    (instances
      (project "kria-k26-devboard"
        (path "" (page "11"))
      )
    )
  )

  (sheet (at 110.49 49.53) (size 40.64 31.75) (fields_autoplaced)
    (stroke (width 0) (type solid))
    (fill (color 0 0 0 0.0000))
    (property "Sheetname" "Debug and JTAG" (at 110.49 48.8184 0)
      (effects (font (size 1.27 1.27)) (justify left bottom))
    )
    (property "Sheetfile" "debug.kicad_sch" (at 110.49 81.8646 0)
      (effects (font (size 1.27 1.27)) (justify left top))
    )
    (pin "JTAG_TDO_M2C" input (at 151.13 69.85 0)
      (effects (font (size 1.27 1.27)) (justify right))
    )
    (pin "JTAG_TMS_C2M" input (at 151.13 72.39 0)
      (effects (font (size 1.27 1.27)) (justify right))
    )
    (pin "JTAG_TCK_C2M" input (at 151.13 74.93 0)
      (effects (font (size 1.27 1.27)) (justify right))
    )
    (pin "JTAG_TDI_C2M" input (at 151.13 77.47 0)
      (effects (font (size 1.27 1.27)) (justify right))
    )
    (pin "MIO37" input (at 151.13 67.31 0)
      (effects (font (size 1.27 1.27)) (justify right))
    )
    (pin "MIO36" input (at 151.13 64.77 0)
      (effects (font (size 1.27 1.27)) (justify right))
    )
    (pin "~{PS_POR}" input (at 110.49 80.01 180)
      (effects (font (size 1.27 1.27)) (justify left))
    )
    (pin "~{EEPROM_WC}" input (at 110.49 77.47 180)
      (effects (font (size 1.27 1.27)) (justify left))
    )
    (pin "USBC_CC[1..2]" input (at 151.13 53.34 0)
      (effects (font (size 1.27 1.27)) (justify right))
    )
    (pin "USBC_VBUS" input (at 151.13 50.8 0)
      (effects (font (size 1.27 1.27)) (justify right))
    )
    (pin "USBC_P" input (at 151.13 60.96 0)
      (effects (font (size 1.27 1.27)) (justify right))
    )
    (pin "USBC_N" input (at 151.13 57.15 0)
      (effects (font (size 1.27 1.27)) (justify right))
    )
    (pin "PD_EN" output (at 110.49 52.07 180)
      (effects (font (size 1.27 1.27)) (justify left))
    )
    (pin "~{PS_SRST_C2M}" input (at 151.13 80.01 0)
      (effects (font (size 1.27 1.27)) (justify right))
    )
    (instances
      (project "kria-k26-devboard"
        (path "" (page "8"))
      )
    )
  )

  (sheet (at 250.19 118.11) (size 43.18 33.02) (fields_autoplaced)
    (stroke (width 0) (type solid))
    (fill (color 0 0 0 0.0000))
    (property "Sheetname" "PCIE M2 key E " (at 250.19 117.3984 0)
      (effects (font (size 1.27 1.27)) (justify left bottom))
    )
    (property "Sheetfile" "pcie-m2-key-e.kicad_sch" (at 250.19 151.7146 0)
      (effects (font (size 1.27 1.27)) (justify left top))
    )
    (pin "GTR_DP3_C2M_P" input (at 250.19 129.54 180)
      (effects (font (size 1.27 1.27)) (justify left))
    )
    (pin "GTR_DP3_C2M_N" input (at 250.19 133.35 180)
      (effects (font (size 1.27 1.27)) (justify left))
    )
    (pin "GTR_DP3_M2C_P" input (at 250.19 137.16 180)
      (effects (font (size 1.27 1.27)) (justify left))
    )
    (pin "GTR_DP3_M2C_N" input (at 250.19 140.97 180)
      (effects (font (size 1.27 1.27)) (justify left))
    )
    (pin "GTR_REFCLK3_P" input (at 250.19 144.78 180)
      (effects (font (size 1.27 1.27)) (justify left))
    )
    (pin "GTR_REFCLK3_N" input (at 250.19 148.59 180)
      (effects (font (size 1.27 1.27)) (justify left))
    )
    (pin "M2_USB_P" input (at 293.37 120.65 0)
      (effects (font (size 1.27 1.27)) (justify right))
    )
    (pin "M2_USB_N" input (at 293.37 124.46 0)
      (effects (font (size 1.27 1.27)) (justify right))
    )
    (pin "~{M2_CLKREQ}" input (at 293.37 147.32 0)
      (effects (font (size 1.27 1.27)) (justify right))
    )
    (pin "~{M2_PERST}" input (at 293.37 144.78 0)
      (effects (font (size 1.27 1.27)) (justify right))
    )
    (instances
      (project "kria-k26-devboard"
        (path "" (page "16"))
      )
    )
  )

  (sheet (at 250.19 77.47) (size 43.18 8.89) (fields_autoplaced)
    (stroke (width 0) (type solid))
    (fill (color 0 0 0 0.0000))
    (property "Sheetname" "SD 3.0 card" (at 250.19 76.7584 0)
      (effects (font (size 1.27 1.27)) (justify left bottom))
    )
    (property "Sheetfile" "sd-3-card.kicad_sch" (at 250.19 86.9446 0)
      (effects (font (size 1.27 1.27)) (justify left top))
    )
    (pin "MIO[45..51]" input (at 250.19 80.01 180)
      (effects (font (size 1.27 1.27)) (justify left))
    )
    (pin "MIO39" input (at 250.19 82.55 180)
      (effects (font (size 1.27 1.27)) (justify left))
    )
    (pin "~{SD_CARD_RESET}" input (at 293.37 80.01 0)
      (effects (font (size 1.27 1.27)) (justify right))
    )
    (instances
      (project "kria-k26-devboard"
        (path "" (page "14"))
      )
    )
  )

  (sheet (at 250.19 213.36) (size 43.18 11.43) (fields_autoplaced)
    (stroke (width 0) (type solid))
    (fill (color 0 0 0 0.0000))
    (property "Sheetname" "I2C " (at 250.19 212.6484 0)
      (effects (font (size 1.27 1.27)) (justify left bottom))
    )
    (property "Sheetfile" "i2c.kicad_sch" (at 250.19 225.3746 0)
      (effects (font (size 1.27 1.27)) (justify left top))
    )
    (pin "MIO24_I2C_SCK" input (at 250.19 215.9 180)
      (effects (font (size 1.27 1.27)) (justify left))
    )
    (pin "~{EEPROM_WC}" input (at 250.19 222.25 180)
      (effects (font (size 1.27 1.27)) (justify left))
    )
    (pin "MIO25_I2C_SDA" input (at 250.19 218.44 180)
      (effects (font (size 1.27 1.27)) (justify left))
    )
    (instances
      (project "kria-k26-devboard"
        (path "" (page "18"))
      )
    )
  )

  (sheet (at 250.19 156.21) (size 43.18 52.07) (fields_autoplaced)
    (stroke (width 0) (type solid))
    (fill (color 0 0 0 0.0000))
    (property "Sheetname" "Clock distribution" (at 250.19 155.4984 0)
      (effects (font (size 1.27 1.27)) (justify left bottom))
    )
    (property "Sheetfile" "clock.kicad_sch" (at 250.19 208.8646 0)
      (effects (font (size 1.27 1.27)) (justify left top))
    )
    (pin "GTR_REFCLK3_P" input (at 250.19 162.56 180)
      (effects (font (size 1.27 1.27)) (justify left))
    )
    (pin "GTR_REFCLK3_N" input (at 250.19 158.75 180)
      (effects (font (size 1.27 1.27)) (justify left))
    )
    (pin "GTR_REFCLK3_C2M_P" input (at 250.19 166.37 180)
      (effects (font (size 1.27 1.27)) (justify left))
    )
    (pin "GTR_REFCLK3_C2M_N" input (at 250.19 170.18 180)
      (effects (font (size 1.27 1.27)) (justify left))
    )
    (pin "GTR_REFCLK2_C2M_P" input (at 250.19 173.99 180)
      (effects (font (size 1.27 1.27)) (justify left))
    )
    (pin "GTR_REFCLK2_C2M_N" input (at 250.19 177.8 180)
      (effects (font (size 1.27 1.27)) (justify left))
    )
    (pin "PS_CLK_EN" input (at 250.19 205.74 180)
      (effects (font (size 1.27 1.27)) (justify left))
    )
    (pin "GTR_REFCLK1_C2M_P" input (at 250.19 181.61 180)
      (effects (font (size 1.27 1.27)) (justify left))
    )
    (pin "GTR_REFCLK1_C2M_N" input (at 250.19 185.42 180)
      (effects (font (size 1.27 1.27)) (justify left))
    )
    (pin "GTR_REFCLK0_C2M_P" input (at 250.19 189.23 180)
      (effects (font (size 1.27 1.27)) (justify left))
    )
    (pin "GTR_REFCLK0_C2M_N" input (at 250.19 193.04 180)
      (effects (font (size 1.27 1.27)) (justify left))
    )
    (pin "~{M2_CLKREQ}" input (at 293.37 160.02 0)
      (effects (font (size 1.27 1.27)) (justify right))
    )
    (instances
      (project "kria-k26-devboard"
        (path "" (page "17"))
      )
    )
  )

  (sheet (at 250.19 16.51) (size 43.18 16.51) (fields_autoplaced)
    (stroke (width 0) (type solid))
    (fill (color 0 0 0 0.0000))
    (property "Sheetname" "Ethernet" (at 250.19 15.7984 0)
      (effects (font (size 1.27 1.27)) (justify left bottom))
    )
    (property "Sheetfile" "eth.kicad_sch" (at 250.19 33.6046 0)
      (effects (font (size 1.27 1.27)) (justify left top))
    )
    (pin "MIO[64..77]" input (at 250.19 30.48 180)
      (effects (font (size 1.27 1.27)) (justify left))
    )
    (pin "POE_VC[1..4]" input (at 250.19 17.78 180)
      (effects (font (size 1.27 1.27)) (justify left))
    )
    (pin "~{ETH_RESET}" input (at 293.37 19.05 0)
      (effects (font (size 1.27 1.27)) (justify right))
    )
    (instances
      (project "kria-k26-devboard"
        (path "" (page "12"))
      )
    )
  )

  (sheet (at 110.49 16.51) (size 40.64 27.94) (fields_autoplaced)
    (stroke (width 0) (type solid))
    (fill (color 0 0 0 0.0000))
    (property "Sheetname" "Power Supply" (at 110.49 15.7984 0)
      (effects (font (size 1.27 1.27)) (justify left bottom))
    )
    (property "Sheetfile" "supply.kicad_sch" (at 110.49 45.0346 0)
      (effects (font (size 1.27 1.27)) (justify left top))
    )
    (pin "VCCOEN_PS_M2C" input (at 151.13 27.94 0)
      (effects (font (size 1.27 1.27)) (justify right))
    )
    (pin "VCCOEN_PL_M2C" input (at 151.13 30.48 0)
      (effects (font (size 1.27 1.27)) (justify right))
    )
    (pin "POE_VC[1..4]" input (at 151.13 17.78 0)
      (effects (font (size 1.27 1.27)) (justify right))
    )
    (pin "USBC_CC[1..2]" input (at 151.13 39.37 0)
      (effects (font (size 1.27 1.27)) (justify right))
    )
    (pin "USBC_P" input (at 151.13 33.02 0)
      (effects (font (size 1.27 1.27)) (justify right))
    )
    (pin "USBC_N" input (at 151.13 36.83 0)
      (effects (font (size 1.27 1.27)) (justify right))
    )
    (pin "USBC_VBUS" input (at 151.13 41.91 0)
      (effects (font (size 1.27 1.27)) (justify right))
    )
    (pin "PD_EN" input (at 110.49 41.91 180)
      (effects (font (size 1.27 1.27)) (justify left))
    )
    (pin "PS_ETH_EN" input (at 110.49 39.37 180)
      (effects (font (size 1.27 1.27)) (justify left))
    )
    (instances
      (project "kria-k26-devboard"
        (path "" (page "2"))
      )
    )
  )

  (sheet (at 250.19 48.26) (size 43.18 22.86) (fields_autoplaced)
    (stroke (width 0) (type solid))
    (fill (color 0 0 0 0.0000))
    (property "Sheetname" "USB" (at 250.19 47.5484 0)
      (effects (font (size 1.27 1.27)) (justify left bottom))
    )
    (property "Sheetfile" "usb.kicad_sch" (at 250.19 71.7046 0)
      (effects (font (size 1.27 1.27)) (justify left top))
    )
    (pin "MIO[52..63]" bidirectional (at 250.19 66.04 180)
      (effects (font (size 1.27 1.27)) (justify left))
    )
    (pin "GTR_DP2_C2M_P" input (at 250.19 58.42 180)
      (effects (font (size 1.27 1.27)) (justify left))
    )
    (pin "GTR_DP2_C2M_N" input (at 250.19 62.23 180)
      (effects (font (size 1.27 1.27)) (justify left))
    )
    (pin "GTR_DP2_M2C_P" input (at 250.19 50.8 180)
      (effects (font (size 1.27 1.27)) (justify left))
    )
    (pin "GTR_DP2_M2C_N" input (at 250.19 54.61 180)
      (effects (font (size 1.27 1.27)) (justify left))
    )
    (pin "~{USB_PHY_RESET}" input (at 293.37 50.8 0)
      (effects (font (size 1.27 1.27)) (justify right))
    )
    (pin "~{USB_HUB_RESET}" input (at 293.37 54.61 0)
      (effects (font (size 1.27 1.27)) (justify right))
    )
    (pin "USB5_P" input (at 293.37 69.85 0)
      (effects (font (size 1.27 1.27)) (justify right))
    )
    (pin "USB5_N" input (at 293.37 66.04 0)
      (effects (font (size 1.27 1.27)) (justify right))
    )
    (instances
      (project "kria-k26-devboard"
        (path "" (page "13"))
      )
    )
  )

  (sheet (at 250.19 91.44) (size 43.18 21.59) (fields_autoplaced)
    (stroke (width 0) (type solid))
    (fill (color 0 0 0 0.0000))
    (property "Sheetname" "Display Port" (at 250.19 90.7284 0)
      (effects (font (size 1.27 1.27)) (justify left bottom))
    )
    (property "Sheetfile" "dp.kicad_sch" (at 250.19 113.6146 0)
      (effects (font (size 1.27 1.27)) (justify left top))
    )
    (pin "MIO[27..30]" input (at 250.19 93.98 180)
      (effects (font (size 1.27 1.27)) (justify left))
    )
    (pin "GTR_DP1_M2C_P" input (at 250.19 105.41 180)
      (effects (font (size 1.27 1.27)) (justify left))
    )
    (pin "GTR_DP1_M2C_N" input (at 250.19 109.22 180)
      (effects (font (size 1.27 1.27)) (justify left))
    )
    (pin "GTR_DP0_M2C_P" input (at 250.19 97.79 180)
      (effects (font (size 1.27 1.27)) (justify left))
    )
    (pin "GTR_DP0_M2C_N" input (at 250.19 101.6 180)
      (effects (font (size 1.27 1.27)) (justify left))
    )
    (instances
      (project "kria-k26-devboard"
        (path "" (page "15"))
      )
    )
  )

  (sheet (at 110.49 87.63) (size 40.64 105.41) (fields_autoplaced)
    (stroke (width 0) (type solid))
    (fill (color 0 0 0 0.0000))
    (property "Sheetname" "Camera interface" (at 110.49 86.9184 0)
      (effects (font (size 1.27 1.27)) (justify left bottom))
    )
    (property "Sheetfile" "camera.kicad_sch" (at 110.49 193.6246 0)
      (effects (font (size 1.27 1.27)) (justify left top))
    )
    (pin "HPA00_CC_P" input (at 151.13 88.9 0)
      (effects (font (size 1.27 1.27)) (justify right))
    )
    (pin "HPA00_CC_N" input (at 151.13 92.71 0)
      (effects (font (size 1.27 1.27)) (justify right))
    )
    (pin "HPA01_P" input (at 151.13 96.52 0)
      (effects (font (size 1.27 1.27)) (justify right))
    )
    (pin "HPA01_N" input (at 151.13 100.33 0)
      (effects (font (size 1.27 1.27)) (justify right))
    )
    (pin "HPA02_P" input (at 151.13 104.14 0)
      (effects (font (size 1.27 1.27)) (justify right))
    )
    (pin "HPA02_N" input (at 151.13 107.95 0)
      (effects (font (size 1.27 1.27)) (justify right))
    )
    (pin "HPA03_P" input (at 151.13 111.76 0)
      (effects (font (size 1.27 1.27)) (justify right))
    )
    (pin "HPA03_N" input (at 151.13 115.57 0)
      (effects (font (size 1.27 1.27)) (justify right))
    )
    (pin "HPA04_P" input (at 151.13 119.38 0)
      (effects (font (size 1.27 1.27)) (justify right))
    )
    (pin "HPA04_N" input (at 151.13 123.19 0)
      (effects (font (size 1.27 1.27)) (justify right))
    )
    (pin "HPA05_CC_P" input (at 151.13 127 0)
      (effects (font (size 1.27 1.27)) (justify right))
    )
    (pin "HPA05_CC_N" input (at 151.13 130.81 0)
      (effects (font (size 1.27 1.27)) (justify right))
    )
    (pin "HPA06_P" input (at 151.13 134.62 0)
      (effects (font (size 1.27 1.27)) (justify right))
    )
    (pin "HPA06_N" input (at 151.13 138.43 0)
      (effects (font (size 1.27 1.27)) (justify right))
    )
    (pin "HPA07_P" input (at 151.13 142.24 0)
      (effects (font (size 1.27 1.27)) (justify right))
    )
    (pin "HPA08_P" input (at 151.13 149.86 0)
      (effects (font (size 1.27 1.27)) (justify right))
    )
    (pin "HPA08_N" input (at 151.13 153.67 0)
      (effects (font (size 1.27 1.27)) (justify right))
    )
    (pin "HPA09_P" input (at 151.13 157.48 0)
      (effects (font (size 1.27 1.27)) (justify right))
    )
    (pin "HPA09_N" input (at 151.13 161.29 0)
      (effects (font (size 1.27 1.27)) (justify right))
    )
    (pin "HPA07_N" input (at 151.13 146.05 0)
      (effects (font (size 1.27 1.27)) (justify right))
    )
    (pin "HDA01" input (at 151.13 166.37 0)
      (effects (font (size 1.27 1.27)) (justify right))
    )
    (pin "HDA00_CC" input (at 151.13 168.91 0)
      (effects (font (size 1.27 1.27)) (justify right))
    )
    (pin "CAM0_VSYNC" input (at 151.13 172.72 0)
      (effects (font (size 1.27 1.27)) (justify right))
    )
    (pin "CAM1_VSYNC" input (at 151.13 175.26 0)
      (effects (font (size 1.27 1.27)) (justify right))
    )
    (pin "CAM0_RST" input (at 151.13 185.42 0)
      (effects (font (size 1.27 1.27)) (justify right))
    )
    (instances
      (project "kria-k26-devboard"
        (path "" (page "9"))
      )
    )
  )

  (sheet (at 250.19 229.87) (size 43.18 7.62) (fields_autoplaced)
    (stroke (width 0) (type solid))
    (fill (color 0 0 0 0.0000))
    (property "Sheetname" "PMOD" (at 250.19 229.1584 0)
      (effects (font (size 1.27 1.27)) (justify left bottom))
    )
    (property "Sheetfile" "pmod.kicad_sch" (at 250.19 238.0746 0)
      (effects (font (size 1.27 1.27)) (justify left top))
    )
    (pin "HDA[11..18]" input (at 250.19 232.41 180)
      (effects (font (size 1.27 1.27)) (justify left))
    )
    (pin "HDA16_CC" input (at 250.19 234.95 180)
      (effects (font (size 1.27 1.27)) (justify left))
    )
    (instances
      (project "kria-k26-devboard"
        (path "" (page "19"))
      )
    )
  )

  (sheet (at 110.49 199.39) (size 40.64 39.37) (fields_autoplaced)
    (stroke (width 0) (type solid))
    (fill (color 0 0 0 0.0000))
    (property "Sheetname" "Reset logic" (at 110.49 198.6784 0)
      (effects (font (size 1.27 1.27)) (justify left bottom))
    )
    (property "Sheetfile" "reset.kicad_sch" (at 110.49 239.3446 0)
      (effects (font (size 1.27 1.27)) (justify left top))
    )
    (pin "MIO43" input (at 151.13 218.44 0)
      (effects (font (size 1.27 1.27)) (justify right))
    )
    (pin "MIO44" input (at 151.13 220.98 0)
      (effects (font (size 1.27 1.27)) (justify right))
    )
    (pin "MIO38" input (at 151.13 213.36 0)
      (effects (font (size 1.27 1.27)) (justify right))
    )
    (pin "HDA02" input (at 151.13 224.79 0)
      (effects (font (size 1.27 1.27)) (justify right))
    )
    (pin "~{PS_POR}" input (at 151.13 209.55 0)
      (effects (font (size 1.27 1.27)) (justify right))
    )
    (pin "~{USB_PHY_RESET}" input (at 151.13 233.68 0)
      (effects (font (size 1.27 1.27)) (justify right))
    )
    (pin "~{USB_HUB_RESET}" input (at 151.13 231.14 0)
      (effects (font (size 1.27 1.27)) (justify right))
    )
    (pin "~{ETH_RESET}" input (at 151.13 236.22 0)
      (effects (font (size 1.27 1.27)) (justify right))
    )
    (pin "~{SD_CARD_RESET}" input (at 151.13 228.6 0)
      (effects (font (size 1.27 1.27)) (justify right))
    )
    (pin "PS_CLOCK_EN" input (at 110.49 236.22 180)
      (effects (font (size 1.27 1.27)) (justify left))
    )
    (pin "MIO41" input (at 151.13 215.9 0)
      (effects (font (size 1.27 1.27)) (justify right))
    )
    (pin "~{M2_PERST}" input (at 110.49 233.68 180)
      (effects (font (size 1.27 1.27)) (justify left))
    )
    (pin "CAM_RST" input (at 151.13 201.93 0)
      (effects (font (size 1.27 1.27)) (justify right))
    )
    (instances
      (project "kria-k26-devboard"
        (path "" (page "10"))
      )
    )
  )

  (sheet_instances
    (path "/" (page "1"))
  )
)
